# S9S_MB_2U (Grand Teton) — schematic netlist excerpt (pin names and nets, part order shuffled) for the footprints in the layout excerpt that follows; sources: Cadence DE-HDL packaged netlist, KiCad conversion of 03242023_DA0F0TMBIJ0_F0T_Motherboard_J_brd_V01_OCP.brd

PR4011  Q_RES  10K 1% CHIP  pkg 0402LF  page 242 : A = P12V_SCM_OV_FB ; B = GND
H21  HOLE  EMPTY  pkg TH  page 311 : \1\ = NC
R4623  Q_RES  1K 1% CHIP  pkg 0402LF  page 248 : A = P3V3_AUX ; B = PU_JTAG_SW_PU
U1_DC  TP  NA  pkg TP_BOM ONLY  page 312 : TP = NC

(kicad_pcb
	(version 20260206)
	(generator "pcbnew")
	(generator_version "10.0")
	(general
		(thickness 1.6)
		(legacy_teardrops no)
	)
	(paper "A4")
	(title_block
		(title "03242023_DA0F0TMBIJ0_F0T_Motherboard_J_brd_V01_OCP.brd")
		(comment 1 "Grand Teton / footprints 3477-3480 of 6105")
	)
	(layers
		(0 "F.Cu" signal "TOP")
		(4 "In1.Cu" signal "GND")
		(6 "In2.Cu" signal "IN1")
		(8 "In3.Cu" signal "GND1")
		(10 "In4.Cu" signal "IN2")
		(12 "In5.Cu" signal "GND2")
		(14 "In6.Cu" signal "IN3")
		(16 "In7.Cu" signal "GND3")
		(18 "In8.Cu" signal "VCC")
		(20 "In9.Cu" signal "VCC1")
		(22 "In10.Cu" signal "GND4")
		(24 "In11.Cu" signal "IN4")
		(26 "In12.Cu" signal "GND5")
		(28 "In13.Cu" signal "IN5")
		(30 "In14.Cu" signal "GND6")
		(32 "In15.Cu" signal "IN6")
		(34 "In16.Cu" signal "GND7")
		(2 "B.Cu" signal "BOTTOM")
		(9 "F.Adhes" user "F.Adhesive")
		(11 "B.Adhes" user "B.Adhesive")
		(13 "F.Paste" user "Package Geometry/Pastemask Top")
		(15 "B.Paste" user "Package Geometry/Pastemask Bottom")
		(5 "F.SilkS" user "Ref Des/Silkscreen Top")
		(7 "B.SilkS" user "Ref Des/Silkscreen Bottom")
		(1 "F.Mask" user "Board Geometry/Soldermask Top")
		(3 "B.Mask" user "Board Geometry/Soldermask Bottom")
		(17 "Dwgs.User" user "User.Drawings")
		(19 "Cmts.User" user "User.Comments")
		(21 "Eco1.User" user "User.Eco1")
		(23 "Eco2.User" user "User.Eco2")
		(25 "Edge.Cuts" user "Board Geometry/Outline")
		(27 "Margin" user)
		(31 "F.CrtYd" user "Package Geometry/Place Bound Top")
		(29 "B.CrtYd" user "Package Geometry/Place Bound Bottom")
		(35 "F.Fab" user "Ref Des/Assembly Top")
		(33 "B.Fab" user "Ref Des/Assembly Bottom")
	)
	(footprint ""
		(layer "F.Cu")
		(at 120.269 -60.035948 90)
		(property "Reference" "R4623"
			(at 0 0 90)
			(layer "F.SilkS")
			(hide yes)
			(effects
				(font
					(size 1.27 1.27)
				)
			)
		)
		(property "Value" ""
			(at 0 0 90)
			(layer "F.Fab")
			(effects
				(font
					(size 1.27 1.27)
				)
			)
		)
		(duplicate_pad_numbers_are_jumpers no)
		(fp_line
			(start 0.7874 -0.4064)
			(end 0.7874 0.4064)
			(stroke
				(width 0.1524)
				(type default)
			)
			(layer "F.SilkS")
		)
		(fp_line
			(start -0.7874 -0.4064)
			(end 0.7874 -0.4064)
			(stroke
				(width 0.1524)
				(type default)
			)
			(layer "F.SilkS")
		)
		(fp_line
			(start 0.7874 0.4064)
			(end -0.7874 0.4064)
			(stroke
				(width 0.1524)
				(type default)
			)
			(layer "F.SilkS")
		)
		(fp_line
			(start -0.7874 0.4064)
			(end -0.7874 -0.4064)
			(stroke
				(width 0.1524)
				(type default)
			)
			(layer "F.SilkS")
		)
		(fp_line
			(start -0.12065 -0.305054)
			(end -0.12065 -0.2794)
			(stroke
				(width 0.1)
				(type default)
			)
			(layer "F.Fab")
		)
		(fp_line
			(start -0.67945 -0.305054)
			(end -0.12065 -0.305054)
			(stroke
				(width 0.1)
				(type default)
			)
			(layer "F.Fab")
		)
		(fp_line
			(start 0.67945 -0.3048)
			(end 0.67945 0.3048)
			(stroke
				(width 0.1)
				(type default)
			)
			(layer "F.Fab")
		)
		(fp_line
			(start 0.12065 -0.3048)
			(end 0.67945 -0.3048)
			(stroke
				(width 0.1)
				(type default)
			)
			(layer "F.Fab")
		)
		(fp_line
			(start 0.12065 -0.2794)
			(end 0.12065 -0.3048)
			(stroke
				(width 0.1)
				(type default)
			)
			(layer "F.Fab")
		)
		(fp_line
			(start -0.12065 -0.2794)
			(end 0.12065 -0.2794)
			(stroke
				(width 0.1)
				(type default)
			)
			(layer "F.Fab")
		)
		(fp_line
			(start 0.120396 0.2794)
			(end -0.12065 0.2794)
			(stroke
				(width 0.1)
				(type default)
			)
			(layer "F.Fab")
		)
		(fp_line
			(start -0.12065 0.2794)
			(end -0.12065 0.3048)
			(stroke
				(width 0.1)
				(type default)
			)
			(layer "F.Fab")
		)
		(fp_line
			(start 0.67945 0.3048)
			(end 0.120396 0.3048)
			(stroke
				(width 0.1)
				(type default)
			)
			(layer "F.Fab")
		)
		(fp_line
			(start 0.120396 0.3048)
			(end 0.120396 0.2794)
			(stroke
				(width 0.1)
				(type default)
			)
			(layer "F.Fab")
		)
		(fp_line
			(start -0.12065 0.3048)
			(end -0.67945 0.3048)
			(stroke
				(width 0.1)
				(type default)
			)
			(layer "F.Fab")
		)
		(fp_line
			(start -0.67945 0.3048)
			(end -0.67945 -0.305054)
			(stroke
				(width 0.1)
				(type default)
			)
			(layer "F.Fab")
		)
		(pad "1" smd circle
			(at -0.40005 0 90)
			(size 0 0)
			(layers "F.Cu" "F.Mask" "F.Paste")
			(net "P3V3_AUX")
		)
		(pad "2" smd circle
			(at 0.40005 0 90)
			(size 0 0)
			(layers "F.Cu" "F.Mask" "F.Paste")
			(net "PU_JTAG_SW_PU")
		)
	)
	(footprint ""
		(layer "F.Cu")
		(at 382.875028 -206.024734)
		(property "Reference" "H21"
			(at 5.236972 -2.066544 0)
			(unlocked yes)
			(layer "F.SilkS")
			(effects
				(font
					(size 0.7874 0.5842)
					(thickness 0.1524)
				)
				(justify left)
			)
		)
		(property "Value" ""
			(at 0 0 0)
			(layer "F.Fab")
			(effects
				(font
					(size 1.27 1.27)
				)
			)
		)
		(duplicate_pad_numbers_are_jumpers no)
		(fp_arc
			(start -1.202944 -2.222754)
			(mid 1.293612 -2.171092)
			(end 2.5273 0)
			(stroke
				(width 0.1524)
				(type default)
			)
			(layer "F.SilkS")
		)
		(fp_arc
			(start 2.5273 0)
			(mid 0.497397 2.477827)
			(end -2.331466 0.97536)
			(stroke
				(width 0.1524)
				(type default)
			)
			(layer "F.SilkS")
		)
		(fp_circle
			(center 0 0)
			(end 2.5273 0)
			(stroke
				(width 0.1524)
				(type default)
			)
			(fill no)
			(layer "B.SilkS")
		)
		(fp_circle
			(center 0 0)
			(end 2.5273 0)
			(stroke
				(width 0.1)
				(type default)
			)
			(fill no)
			(layer "B.Fab")
		)
		(fp_circle
			(center 0 0)
			(end 2.5273 0)
			(stroke
				(width 0.1)
				(type default)
			)
			(fill no)
			(layer "F.Fab")
		)
		(pad "" np_thru_hole circle
			(at 0 0)
			(size 3.429 3.429)
			(drill 3.429)
			(layers "*.Cu" "*.Mask")
			(clearance 0.381)
			(thermal_gap 0.381)
		)
	)
	(footprint ""
		(layer "F.Cu")
		(at 173.899322 -28.03779 -90)
		(property "Reference" "PR4011"
			(at 0 0 270)
			(layer "F.SilkS")
			(hide yes)
			(effects
				(font
					(size 1.27 1.27)
				)
			)
		)
		(property "Value" ""
			(at 0 0 270)
			(layer "F.Fab")
			(effects
				(font
					(size 1.27 1.27)
				)
			)
		)
		(duplicate_pad_numbers_are_jumpers no)
		(fp_line
			(start -0.7874 0.4064)
			(end -0.7874 -0.4064)
			(stroke
				(width 0.1524)
				(type default)
			)
			(layer "F.SilkS")
		)
		(fp_line
			(start 0.7874 0.4064)
			(end -0.7874 0.4064)
			(stroke
				(width 0.1524)
				(type default)
			)
			(layer "F.SilkS")
		)
		(fp_line
			(start -0.7874 -0.4064)
			(end 0.7874 -0.4064)
			(stroke
				(width 0.1524)
				(type default)
			)
			(layer "F.SilkS")
		)
		(fp_line
			(start 0.7874 -0.4064)
			(end 0.7874 0.4064)
			(stroke
				(width 0.1524)
				(type default)
			)
			(layer "F.SilkS")
		)
		(fp_line
			(start -0.67945 0.3048)
			(end -0.67945 -0.305054)
			(stroke
				(width 0.1)
				(type default)
			)
			(layer "F.Fab")
		)
		(fp_line
			(start -0.12065 0.3048)
			(end -0.67945 0.3048)
			(stroke
				(width 0.1)
				(type default)
			)
			(layer "F.Fab")
		)
		(fp_line
			(start 0.120396 0.3048)
			(end 0.120396 0.2794)
			(stroke
				(width 0.1)
				(type default)
			)
			(layer "F.Fab")
		)
		(fp_line
			(start 0.67945 0.3048)
			(end 0.120396 0.3048)
			(stroke
				(width 0.1)
				(type default)
			)
			(layer "F.Fab")
		)
		(fp_line
			(start -0.12065 0.2794)
			(end -0.12065 0.3048)
			(stroke
				(width 0.1)
				(type default)
			)
			(layer "F.Fab")
		)
		(fp_line
			(start 0.120396 0.2794)
			(end -0.12065 0.2794)
			(stroke
				(width 0.1)
				(type default)
			)
			(layer "F.Fab")
		)
		(fp_line
			(start -0.12065 -0.2794)
			(end 0.12065 -0.2794)
			(stroke
				(width 0.1)
				(type default)
			)
			(layer "F.Fab")
		)
		(fp_line
			(start 0.12065 -0.2794)
			(end 0.12065 -0.3048)
			(stroke
				(width 0.1)
				(type default)
			)
			(layer "F.Fab")
		)
		(fp_line
			(start 0.12065 -0.3048)
			(end 0.67945 -0.3048)
			(stroke
				(width 0.1)
				(type default)
			)
			(layer "F.Fab")
		)
		(fp_line
			(start 0.67945 -0.3048)
			(end 0.67945 0.3048)
			(stroke
				(width 0.1)
				(type default)
			)
			(layer "F.Fab")
		)
		(fp_line
			(start -0.67945 -0.305054)
			(end -0.12065 -0.305054)
			(stroke
				(width 0.1)
				(type default)
			)
			(layer "F.Fab")
		)
		(fp_line
			(start -0.12065 -0.305054)
			(end -0.12065 -0.2794)
			(stroke
				(width 0.1)
				(type default)
			)
			(layer "F.Fab")
		)
		(pad "1" smd circle
			(at -0.40005 0 270)
			(size 0 0)
			(layers "F.Cu" "F.Mask" "F.Paste")
			(net "P12V_SCM_OV_FB")
		)
		(pad "2" smd circle
			(at 0.40005 0 270)
			(size 0 0)
			(layers "F.Cu" "F.Mask" "F.Paste")
			(net "GND")
		)
	)
	(footprint ""
		(layer "F.Cu")
		(at 492.12627 -468.00135)
		(property "Reference" "U1_DC"
			(at -0.90551 1.402842 0)
			(unlocked yes)
			(layer "F.SilkS")
			(effects
				(font
					(size 0.7874 0.5842)
					(thickness 0.1524)
				)
				(justify left)
			)
		)
		(property "Value" ""
			(at 0 0 0)
			(layer "F.Fab")
			(effects
				(font
					(size 1.27 1.27)
				)
			)
		)
		(duplicate_pad_numbers_are_jumpers no)
		(pad "1" smd circle
			(at 0 0)
			(size 0.762 0.762)
			(layers "F.Cu" "F.Mask" "F.Paste")
			(net "Net_8486")
		)
	)
)
